(kicad_pcb
	(version 20241229)
	(generator "pcbnew")
	(generator_version "9.0")
	(general
		(thickness 1.62)
		(legacy_teardrops no)
	)
	(paper "A4")
	(title_block
		(title "OCuLink to 10GbE adapter")
		(date "2026-02-23")
		(rev "1.1.0")
		(company "Antmicro Ltd")
		(comment 1 "www.antmicro.com")
		(comment 9 "footprints 505-509 of 510")
	)
	(layers
		(0 "F.Cu" signal)
		(4 "In1.Cu" signal)
		(6 "In2.Cu" signal)
		(8 "In3.Cu" signal)
		(10 "In4.Cu" signal)
		(12 "In5.Cu" signal)
		(14 "In6.Cu" signal)
		(2 "B.Cu" signal)
		(9 "F.Adhes" user "F.Adhesive")
		(11 "B.Adhes" user "B.Adhesive")
		(13 "F.Paste" user)
		(15 "B.Paste" user)
		(5 "F.SilkS" user "F.Silkscreen")
		(7 "B.SilkS" user "B.Silkscreen")
		(1 "F.Mask" user)
		(3 "B.Mask" user)
		(17 "Dwgs.User" user "User.Drawings")
		(19 "Cmts.User" user "User.Comments")
		(21 "Eco1.User" user "User.Eco1")
		(23 "Eco2.User" user "User.Eco2")
		(25 "Edge.Cuts" user)
		(27 "Margin" user)
		(31 "F.CrtYd" user "F.Courtyard")
		(29 "B.CrtYd" user "B.Courtyard")
		(35 "F.Fab" user)
		(33 "B.Fab" user)
	)
	(footprint "antmicro-footprints:Oscillator_SMD_Abracon_AX3_3.2x2.5x1mm"
		(layer "B.Cu")
		(at 104.675 89.054 180)
		(property "Reference" "Y3"
			(at 0.725 -2.036 0)
			(layer "B.SilkS")
			(effects
				(font
					(size 0.7 0.7)
					(thickness 0.15)
				)
				(justify right top mirror)
			)
		)
		(property "Value" "Oscillator_100MHz_NX324"
			(at 0 -2.8 0)
			(layer "B.Fab")
			(hide yes)
			(effects
				(font
					(size 0.7 0.7)
					(thickness 0.15)
				)
				(justify left bottom mirror)
			)
		)
		(property "Datasheet" "https://www.diodes.com/assets/Datasheets/NX324.pdf"
			(at 0 0 0)
			(layer "B.Fab")
			(hide yes)
			(effects
				(font
					(size 1.27 1.27)
					(thickness 0.15)
				)
				(justify mirror)
			)
		)
		(property "Description" "100 MHz XO (Standard) HCSL Oscillator 3.3V Enable/Disable 6-SMD, No Lead"
			(at 0 0 0)
			(layer "B.Fab")
			(hide yes)
			(effects
				(font
					(size 1.27 1.27)
					(thickness 0.15)
				)
				(justify mirror)
			)
		)
		(property "Manufacturer" "Diodes Incorporated"
			(at 0 0 0)
			(unlocked yes)
			(layer "B.Fab")
			(hide yes)
			(effects
				(font
					(size 1 1)
					(thickness 0.15)
				)
				(justify mirror)
			)
		)
		(property "MPN" "NX3241E0100.000000"
			(at 0 0 0)
			(unlocked yes)
			(layer "B.Fab")
			(hide yes)
			(effects
				(font
					(size 1 1)
					(thickness 0.15)
				)
				(justify mirror)
			)
		)
		(property "Val" "100 MHz"
			(at 0 0 0)
			(unlocked yes)
			(layer "B.Fab")
			(hide yes)
			(effects
				(font
					(size 1 1)
					(thickness 0.15)
				)
				(justify mirror)
			)
		)
		(property "Author" "Antmicro"
			(at 0 0 0)
			(unlocked yes)
			(layer "B.Fab")
			(hide yes)
			(effects
				(font
					(size 1 1)
					(thickness 0.15)
				)
				(justify mirror)
			)
		)
		(property "License" "Apache-2.0"
			(at 0 0 0)
			(unlocked yes)
			(layer "B.Fab")
			(hide yes)
			(effects
				(font
					(size 1 1)
					(thickness 0.15)
				)
				(justify mirror)
			)
		)
		(sheetname "/X710-AT2 PCIe/")
		(sheetfile "x710-at2-pcie.kicad_sch")
		(attr smd exclude_from_pos_files exclude_from_bom dnp)
		(fp_line
			(start 1.5 1.8)
			(end -1.5 1.8)
			(stroke
				(width 0.12)
				(type solid)
			)
			(layer "B.SilkS")
		)
		(fp_line
			(start 1.5 1.5)
			(end 1.5 1.8)
			(stroke
				(width 0.12)
				(type solid)
			)
			(layer "B.SilkS")
		)
		(fp_line
			(start 1.5 -1.8)
			(end 1.5 -1.5)
			(stroke
				(width 0.12)
				(type solid)
			)
			(layer "B.SilkS")
		)
		(fp_line
			(start -1.5 1.8)
			(end -1.5 1.5)
			(stroke
				(width 0.12)
				(type solid)
			)
			(layer "B.SilkS")
		)
		(fp_line
			(start -1.5 -1.5)
			(end -1.5 -1.8)
			(stroke
				(width 0.12)
				(type solid)
			)
			(layer "B.SilkS")
		)
		(fp_line
			(start -1.5 -1.8)
			(end 1.5 -1.8)
			(stroke
				(width 0.12)
				(type solid)
			)
			(layer "B.SilkS")
		)
		(fp_circle
			(center -1.7 1.9)
			(end -1.7 1.85)
			(stroke
				(width 0.15)
				(type solid)
			)
			(fill yes)
			(layer "B.SilkS")
		)
		(fp_rect
			(start 1.6 1.9)
			(end -1.6 -1.9)
			(stroke
				(width 0.05)
				(type solid)
			)
			(fill no)
			(layer "B.CrtYd")
		)
		(fp_line
			(start -0.6 1.6)
			(end -1.3 0.9)
			(stroke
				(width 0.15)
				(type solid)
			)
			(layer "B.Fab")
		)
		(fp_rect
			(start 1.3 1.601)
			(end -1.3 -1.599)
			(stroke
				(width 0.15)
				(type solid)
			)
			(fill no)
			(layer "B.Fab")
		)
		(pad "1" smd rect
			(at -0.8 1.199 270)
			(size 0.9 1.1)
			(layers "B.Cu" "B.Mask" "B.Paste")
			(net 404 "Net-(Y3-EN)")
			(pinfunction "EN")
			(pintype "input")
		)
		(pad "2" smd rect
			(at -0.8 0 270)
			(size 0.9 1.1)
			(layers "B.Cu" "B.Mask" "B.Paste")
			(net 409 "unconnected-(Y3-NC-Pad2)")
			(pinfunction "NC")
			(pintype "no_connect")
		)
		(pad "3" smd rect
			(at -0.8 -1.199 270)
			(size 0.9 1.1)
			(layers "B.Cu" "B.Mask" "B.Paste")
			(net 28 "GND")
			(pinfunction "GND")
			(pintype "power_in")
		)
		(pad "4" smd rect
			(at 0.801 -1.199 270)
			(size 0.9 1.1)
			(layers "B.Cu" "B.Mask" "B.Paste")
			(net 407 "/X710-AT2 PCIe/GEN_CLK+")
			(pinfunction "OUT+")
			(pintype "output")
		)
		(pad "5" smd rect
			(at 0.801 0 270)
			(size 0.9 1.1)
			(layers "B.Cu" "B.Mask" "B.Paste")
			(net 408 "/X710-AT2 PCIe/GEN_CLK-")
			(pinfunction "OUT-")
			(pintype "output")
		)
		(pad "6" smd rect
			(at 0.801 1.199 270)
			(size 0.9 1.1)
			(layers "B.Cu" "B.Mask" "B.Paste")
			(net 7 "+3V3")
			(pinfunction "VCC")
			(pintype "power_in")
		)
	)
	(footprint "antmicro-footprints:C_0402_1005Metric"
		(layer "B.Cu")
		(at 89.225 94.6 90)
		(descr "Capacitor SMD 0402")
		(tags "capacitor SMD 0402")
		(property "Reference" "C94"
			(at 12.5 -0.462343 90)
			(layer "B.SilkS")
			(effects
				(font
					(size 0.7 0.7)
					(thickness 0.15)
				)
				(justify right top mirror)
			)
		)
		(property "Value" "C_1u_25V_0402"
			(at -1.022927 -2.155213 90)
			(layer "B.Fab")
			(hide yes)
			(effects
				(font
					(size 0.7 0.7)
					(thickness 0.15)
				)
				(justify right top mirror)
			)
		)
		(property "Datasheet" "https://www.murata.com/products/productdetail?partno=GRM155R61E105KE11%23"
			(at 0 0 90)
			(layer "B.Fab")
			(hide yes)
			(effects
				(font
					(size 1.27 1.27)
					(thickness 0.15)
				)
				(justify mirror)
			)
		)
		(property "Description" "SMD Multilayer Ceramic Capacitor, 1 µF, 25 V, 0402 [1005 Metric], ± 10%, X5R, GRM Series"
			(at 0 0 90)
			(layer "B.Fab")
			(hide yes)
			(effects
				(font
					(size 1.27 1.27)
					(thickness 0.15)
				)
				(justify mirror)
			)
		)
		(property "MPN" "GRM155R61E105KE11J"
			(at 0 0 90)
			(unlocked yes)
			(layer "B.Fab")
			(hide yes)
			(effects
				(font
					(size 1 1)
					(thickness 0.15)
				)
				(justify mirror)
			)
		)
		(property "Manufacturer" "Murata"
			(at 0 0 90)
			(unlocked yes)
			(layer "B.Fab")
			(hide yes)
			(effects
				(font
					(size 1 1)
					(thickness 0.15)
				)
				(justify mirror)
			)
		)
		(property "License" "Apache-2.0"
			(at 0 0 90)
			(unlocked yes)
			(layer "B.Fab")
			(hide yes)
			(effects
				(font
					(size 1 1)
					(thickness 0.15)
				)
				(justify mirror)
			)
		)
		(property "Author" "Antmicro"
			(at 0 0 90)
			(unlocked yes)
			(layer "B.Fab")
			(hide yes)
			(effects
				(font
					(size 1 1)
					(thickness 0.15)
				)
				(justify mirror)
			)
		)
		(property "Val" "1u"
			(at 0 0 90)
			(unlocked yes)
			(layer "B.Fab")
			(hide yes)
			(effects
				(font
					(size 1 1)
					(thickness 0.15)
				)
				(justify mirror)
			)
		)
		(property "Voltage" "25V"
			(at 0 0 90)
			(unlocked yes)
			(layer "B.Fab")
			(hide yes)
			(effects
				(font
					(size 1 1)
					(thickness 0.15)
				)
				(justify mirror)
			)
		)
		(property "Dielectric" "X5R"
			(at 0 0 90)
			(unlocked yes)
			(layer "B.Fab")
			(hide yes)
			(effects
				(font
					(size 1 1)
					(thickness 0.15)
				)
				(justify mirror)
			)
		)
		(sheetname "/X710-AT2 power/")
		(sheetfile "x710-at2-power.kicad_sch")
		(attr smd)
		(fp_rect
			(start -0.925 0.47)
			(end 0.925 -0.47)
			(stroke
				(width 0.05)
				(type default)
			)
			(fill no)
			(layer "B.CrtYd")
		)
		(fp_line
			(start 0.504 -0.248)
			(end -0.494 -0.248)
			(stroke
				(width 0.15)
				(type solid)
			)
			(layer "B.Fab")
		)
		(fp_line
			(start -0.494 -0.248)
			(end -0.494 0.25)
			(stroke
				(width 0.15)
				(type solid)
			)
			(layer "B.Fab")
		)
		(fp_line
			(start 0.504 0.25)
			(end 0.504 -0.248)
			(stroke
				(width 0.15)
				(type solid)
			)
			(layer "B.Fab")
		)
		(fp_line
			(start -0.494 0.25)
			(end 0.504 0.25)
			(stroke
				(width 0.15)
				(type solid)
			)
			(layer "B.Fab")
		)
		(pad "1" smd roundrect
			(at -0.48 0 90)
			(size 0.59 0.64)
			(layers "B.Cu" "B.Mask" "B.Paste")
			(roundrect_rratio 0.25)
			(net 28 "GND")
			(pintype "passive")
		)
		(pad "2" smd roundrect
			(at 0.48 0 90)
			(size 0.59 0.64)
			(layers "B.Cu" "B.Mask" "B.Paste")
			(roundrect_rratio 0.25)
			(net 1 "VCCA")
			(pintype "passive")
		)
	)
	(footprint "antmicro-footprints:R_0402_1005Metric"
		(layer "B.Cu")
		(at 90.725 107.8 90)
		(descr "Resistor SMD 0402")
		(tags "resistor SMD 0402")
		(property "Reference" "R113"
			(at -1.37 0.665 90)
			(layer "B.SilkS")
			(effects
				(font
					(size 0.7 0.7)
					(thickness 0.15)
				)
				(justify right top mirror)
			)
		)
		(property "Value" "R_1k_0402"
			(at -1.011843 -1.772046 90)
			(layer "B.Fab")
			(hide yes)
			(effects
				(font
					(size 0.7 0.7)
					(thickness 0.15)
				)
				(justify right top mirror)
			)
		)
		(property "Datasheet" "https://www.bourns.com/docs/product-datasheets/cr.pdf"
			(at 0 0 90)
			(layer "B.Fab")
			(hide yes)
			(effects
				(font
					(size 1.27 1.27)
					(thickness 0.15)
				)
				(justify mirror)
			)
		)
		(property "Description" "SMD Chip Resistor, 1 kohm, ± 1%, 63 mW, 0402 [1005 Metric], Thick Film, General Purpose"
			(at 0 0 90)
			(layer "B.Fab")
			(hide yes)
			(effects
				(font
					(size 1.27 1.27)
					(thickness 0.15)
				)
				(justify mirror)
			)
		)
		(property "MPN" "CR0402-FX-1001GLF"
			(at 0 0 90)
			(unlocked yes)
			(layer "B.Fab")
			(hide yes)
			(effects
				(font
					(size 1 1)
					(thickness 0.15)
				)
				(justify mirror)
			)
		)
		(property "Manufacturer" "Bourns"
			(at 0 0 90)
			(unlocked yes)
			(layer "B.Fab")
			(hide yes)
			(effects
				(font
					(size 1 1)
					(thickness 0.15)
				)
				(justify mirror)
			)
		)
		(property "License" "Apache-2.0"
			(at 0 0 90)
			(unlocked yes)
			(layer "B.Fab")
			(hide yes)
			(effects
				(font
					(size 1 1)
					(thickness 0.15)
				)
				(justify mirror)
			)
		)
		(property "Author" "Antmicro"
			(at 0 0 90)
			(unlocked yes)
			(layer "B.Fab")
			(hide yes)
			(effects
				(font
					(size 1 1)
					(thickness 0.15)
				)
				(justify mirror)
			)
		)
		(property "Val" "1k"
			(at 0 0 90)
			(unlocked yes)
			(layer "B.Fab")
			(hide yes)
			(effects
				(font
					(size 1 1)
					(thickness 0.15)
				)
				(justify mirror)
			)
		)
		(property "Tolerance" "1%"
			(at 0 0 90)
			(unlocked yes)
			(layer "B.Fab")
			(hide yes)
			(effects
				(font
					(size 1 1)
					(thickness 0.15)
				)
				(justify mirror)
			)
		)
		(sheetname "/X710-AT2 Misc/")
		(sheetfile "x710-at2-mics.kicad_sch")
		(attr smd)
		(fp_rect
			(start -0.925 0.47)
			(end 0.925 -0.47)
			(stroke
				(width 0.05)
				(type default)
			)
			(fill no)
			(layer "B.CrtYd")
		)
		(fp_rect
			(start -0.5 0.25)
			(end 0.5 -0.25)
			(stroke
				(width 0.15)
				(type solid)
			)
			(fill no)
			(layer "B.Fab")
		)
		(pad "1" smd roundrect
			(at -0.48 0 90)
			(size 0.59 0.64)
			(layers "B.Cu" "B.Mask" "B.Paste")
			(roundrect_rratio 0.25)
			(net 28 "GND")
			(pintype "passive")
		)
		(pad "2" smd roundrect
			(at 0.48 0 90)
			(size 0.59 0.64)
			(layers "B.Cu" "B.Mask" "B.Paste")
			(roundrect_rratio 0.25)
			(net 295 "/X710-AT2 Misc/XTAL_BYPASS")
			(pintype "passive")
		)
	)
	(footprint "antmicro-footprints:L_0402_1005Metric"
		(layer "B.Cu")
		(at 88 130.4)
		(descr "Inductor SMD 0402")
		(tags "Inductor SMD 0402")
		(property "Reference" "L7"
			(at -0.979 2.590999 0)
			(layer "B.SilkS")
			(effects
				(font
					(size 0.7 0.7)
					(thickness 0.15)
				)
				(justify right top mirror)
			)
		)
		(property "Value" "L_2n4_0.85A_0402"
			(at 0 -1.399999 0)
			(layer "B.Fab")
			(hide yes)
			(effects
				(font
					(size 0.7 0.7)
					(thickness 0.15)
				)
				(justify right top mirror)
			)
		)
		(property "Datasheet" "https://www.murata.com/products/productdetail?partno=LQW15AN2N4B00%23"
			(at 0 0 0)
			(layer "B.Fab")
			(hide yes)
			(effects
				(font
					(size 1.27 1.27)
					(thickness 0.15)
				)
				(justify mirror)
			)
		)
		(property "Description" "Wirewound Inductor, 2.4 nH, 0.05 ohm, 15 GHz, 850 mA, 0402 [1005 Metric], LQW15AN"
			(at 0 0 0)
			(layer "B.Fab")
			(hide yes)
			(effects
				(font
					(size 1.27 1.27)
					(thickness 0.15)
				)
				(justify mirror)
			)
		)
		(property "Val" "2n4/0.85A"
			(at 0 0 0)
			(unlocked yes)
			(layer "B.Fab")
			(hide yes)
			(effects
				(font
					(size 1 1)
					(thickness 0.15)
				)
				(justify mirror)
			)
		)
		(property "Manufacturer" "Murata"
			(at 0 0 0)
			(unlocked yes)
			(layer "B.Fab")
			(hide yes)
			(effects
				(font
					(size 1 1)
					(thickness 0.15)
				)
				(justify mirror)
			)
		)
		(property "MPN" "LQW15AN2N4B00D"
			(at 0 0 0)
			(unlocked yes)
			(layer "B.Fab")
			(hide yes)
			(effects
				(font
					(size 1 1)
					(thickness 0.15)
				)
				(justify mirror)
			)
		)
		(property "ISat" "0.85 A"
			(at 0 0 0)
			(unlocked yes)
			(layer "B.Fab")
			(hide yes)
			(effects
				(font
					(size 1 1)
					(thickness 0.15)
				)
				(justify mirror)
			)
		)
		(property "IMax" "0.85 A"
			(at 0 0 0)
			(unlocked yes)
			(layer "B.Fab")
			(hide yes)
			(effects
				(font
					(size 1 1)
					(thickness 0.15)
				)
				(justify mirror)
			)
		)
		(property "Size" "1.0x0.5"
			(at 0 0 0)
			(unlocked yes)
			(layer "B.Fab")
			(hide yes)
			(effects
				(font
					(size 1 1)
					(thickness 0.15)
				)
				(justify mirror)
			)
		)
		(property "Author" "Antmicro"
			(at 0 0 0)
			(unlocked yes)
			(layer "B.Fab")
			(hide yes)
			(effects
				(font
					(size 1 1)
					(thickness 0.15)
				)
				(justify mirror)
			)
		)
		(property "License" "Apache-2.0"
			(at 0 0 0)
			(unlocked yes)
			(layer "B.Fab")
			(hide yes)
			(effects
				(font
					(size 1 1)
					(thickness 0.15)
				)
				(justify mirror)
			)
		)
		(sheetname "/2xRJ45/")
		(sheetfile "2xrj45.kicad_sch")
		(attr smd)
		(fp_rect
			(start -0.925 0.47)
			(end 0.925 -0.47)
			(stroke
				(width 0.05)
				(type default)
			)
			(fill no)
			(layer "B.CrtYd")
		)
		(fp_rect
			(start -0.499 0.249)
			(end 0.499 -0.249)
			(stroke
				(width 0.15)
				(type solid)
			)
			(fill no)
			(layer "B.Fab")
		)
		(pad "1" smd roundrect
			(at -0.48 0)
			(size 0.59 0.64)
			(layers "B.Cu" "B.Mask" "B.Paste")
			(roundrect_rratio 0.25)
			(net 301 "+1V88_CT")
			(pintype "passive")
		)
		(pad "2" smd roundrect
			(at 0.48 0)
			(size 0.59 0.64)
			(layers "B.Cu" "B.Mask" "B.Paste")
			(roundrect_rratio 0.25)
			(net 300 "/2xRJ45/P1_CT")
			(pintype "passive")
		)
	)
	(footprint "antmicro-footprints:C_0402_1005Metric"
		(layer "B.Cu")
		(at 104.34 86.654 180)
		(descr "Capacitor SMD 0402")
		(tags "capacitor SMD 0402")
		(property "Reference" "C199"
			(at -0.99 0.654 0)
			(layer "B.SilkS")
			(effects
				(font
					(size 0.7 0.7)
					(thickness 0.15)
				)
				(justify left bottom mirror)
			)
		)
		(property "Value" "C_100n_0402"
			(at -1.022927 -2.155213 0)
			(layer "B.Fab")
			(hide yes)
			(effects
				(font
					(size 0.7 0.7)
					(thickness 0.15)
				)
				(justify left bottom mirror)
			)
		)
		(property "Datasheet" "https://www.murata.com/products/productdetail?partno=GRM155R61H104KE14%23"
			(at 0 0 0)
			(layer "B.Fab")
			(hide yes)
			(effects
				(font
					(size 1.27 1.27)
					(thickness 0.15)
				)
				(justify mirror)
			)
		)
		(property "Description" "SMD Multilayer Ceramic Capacitor, 0.1 µF, 50 V, 0402 [1005 Metric], ± 10%, X5R, GRM Series"
			(at 0 0 0)
			(layer "B.Fab")
			(hide yes)
			(effects
				(font
					(size 1.27 1.27)
					(thickness 0.15)
				)
				(justify mirror)
			)
		)
		(property "MPN" "GRM155R61H104KE14D"
			(at 0 0 0)
			(unlocked yes)
			(layer "B.Fab")
			(hide yes)
			(effects
				(font
					(size 1 1)
					(thickness 0.15)
				)
				(justify mirror)
			)
		)
		(property "Manufacturer" "Murata"
			(at 0 0 0)
			(unlocked yes)
			(layer "B.Fab")
			(hide yes)
			(effects
				(font
					(size 1 1)
					(thickness 0.15)
				)
				(justify mirror)
			)
		)
		(property "License" "Apache-2.0"
			(at 0 0 0)
			(unlocked yes)
			(layer "B.Fab")
			(hide yes)
			(effects
				(font
					(size 1 1)
					(thickness 0.15)
				)
				(justify mirror)
			)
		)
		(property "Author" "Antmicro"
			(at 0 0 0)
			(unlocked yes)
			(layer "B.Fab")
			(hide yes)
			(effects
				(font
					(size 1 1)
					(thickness 0.15)
				)
				(justify mirror)
			)
		)
		(property "Val" "100n"
			(at 0 0 0)
			(unlocked yes)
			(layer "B.Fab")
			(hide yes)
			(effects
				(font
					(size 1 1)
					(thickness 0.15)
				)
				(justify mirror)
			)
		)
		(property "Voltage" "50V"
			(at 0 0 0)
			(unlocked yes)
			(layer "B.Fab")
			(hide yes)
			(effects
				(font
					(size 1 1)
					(thickness 0.15)
				)
				(justify mirror)
			)
		)
		(property "Dielectric" "X5R"
			(at 0 0 0)
			(unlocked yes)
			(layer "B.Fab")
			(hide yes)
			(effects
				(font
					(size 1 1)
					(thickness 0.15)
				)
				(justify mirror)
			)
		)
		(sheetname "/X710-AT2 PCIe/")
		(sheetfile "x710-at2-pcie.kicad_sch")
		(attr smd exclude_from_pos_files exclude_from_bom dnp)
		(fp_rect
			(start -0.925 0.47)
			(end 0.925 -0.47)
			(stroke
				(width 0.05)
				(type default)
			)
			(fill no)
			(layer "B.CrtYd")
		)
		(fp_line
			(start 0.504 0.25)
			(end 0.504 -0.248)
			(stroke
				(width 0.15)
				(type solid)
			)
			(layer "B.Fab")
		)
		(fp_line
			(start 0.504 -0.248)
			(end -0.494 -0.248)
			(stroke
				(width 0.15)
				(type solid)
			)
			(layer "B.Fab")
		)
		(fp_line
			(start -0.494 0.25)
			(end 0.504 0.25)
			(stroke
				(width 0.15)
				(type solid)
			)
			(layer "B.Fab")
		)
		(fp_line
			(start -0.494 -0.248)
			(end -0.494 0.25)
			(stroke
				(width 0.15)
				(type solid)
			)
			(layer "B.Fab")
		)
		(pad "1" smd roundrect
			(at -0.48 0 180)
			(size 0.59 0.64)
			(layers "B.Cu" "B.Mask" "B.Paste")
			(roundrect_rratio 0.25)
			(net 28 "GND")
			(pintype "passive")
		)
		(pad "2" smd roundrect
			(at 0.48 0 180)
			(size 0.59 0.64)
			(layers "B.Cu" "B.Mask" "B.Paste")
			(roundrect_rratio 0.25)
			(net 7 "+3V3")
			(pintype "passive")
		)
	)
)
